# BASEBOARD_FAB2 (Tioga Pass) — schematic netlist excerpt (pin names and nets, part order shuffled) for the footprints in the layout excerpt that follows; sources: Cadence DE-HDL packaged netlist, KiCad conversion of Wiwynn_Tioga_Pass_MB.brd

C9G22  CAP  10.0PF 50V 5% COG  pkg 0402LF  page 169 : A = A_P3V_BAT_SCALED ; B = GND
RT11  RES  0 5.0% CHIP  pkg 0603  page 208 : A = VR_PVCCIN_CPU1_PH3_BOOT ; B = VR_PVCCIN_CPU1_PH3_BOOT_R
C1E2  CAP  0.068UF 50V 20% X7R  pkg 1206  page 200 : A = A_HSC_C ; B = GND

(kicad_pcb
	(version 20260206)
	(generator "pcbnew")
	(generator_version "10.0")
	(general
		(thickness 1.6)
		(legacy_teardrops no)
	)
	(paper "A4")
	(title_block
		(title "Wiwynn_Tioga_Pass_MB.brd")
		(comment 1 "Tioga Pass / footprints 2042-2044 of 4770")
	)
	(layers
		(0 "F.Cu" signal "TOP")
		(4 "In1.Cu" signal "L2GND")
		(6 "In2.Cu" signal "L3")
		(8 "In3.Cu" signal "L4GND")
		(10 "In4.Cu" signal "L5")
		(12 "In5.Cu" signal "L6GND")
		(14 "In6.Cu" signal "L7VCC")
		(16 "In7.Cu" signal "L8VCC")
		(18 "In8.Cu" signal "L9GND")
		(20 "In9.Cu" signal "L10")
		(22 "In10.Cu" signal "L11GND")
		(24 "In11.Cu" signal "L12")
		(26 "In12.Cu" signal "L13GND")
		(2 "B.Cu" signal "BOTTOM")
		(9 "F.Adhes" user "F.Adhesive")
		(11 "B.Adhes" user "B.Adhesive")
		(13 "F.Paste" user "Package Geometry/Pastemask Top")
		(15 "B.Paste" user "Package Geometry/Pastemask Bottom")
		(5 "F.SilkS" user "Ref Des/Silkscreen Top")
		(7 "B.SilkS" user "Ref Des/Silkscreen Bottom")
		(1 "F.Mask" user "Board Geometry/Soldermask Top")
		(3 "B.Mask" user "Board Geometry/Soldermask Bottom")
		(17 "Dwgs.User" user "User.Drawings")
		(19 "Cmts.User" user "User.Comments")
		(21 "Eco1.User" user "User.Eco1")
		(23 "Eco2.User" user "User.Eco2")
		(25 "Edge.Cuts" user "Board Geometry/Outline")
		(27 "Margin" user)
		(31 "F.CrtYd" user "Package Geometry/Place Bound Top")
		(29 "B.CrtYd" user "Package Geometry/Place Bound Bottom")
		(35 "F.Fab" user "Ref Des/Assembly Top")
		(33 "B.Fab" user "Ref Des/Assembly Bottom")
	)
	(footprint ""
		(layer "F.Cu")
		(at 26.416 -64.516)
		(property "Reference" "C1E2"
			(at 0.02667 4.953 90)
			(unlocked yes)
			(layer "F.SilkS")
			(effects
				(font
					(size 0.7874 0.5842)
					(thickness 0.1524)
				)
			)
		)
		(property "Value" ""
			(at 0 0 0)
			(layer "F.Fab")
			(effects
				(font
					(size 1.27 1.27)
				)
			)
		)
		(duplicate_pad_numbers_are_jumpers no)
		(fp_line
			(start -0.9017 1.953006)
			(end -0.9017 0.823976)
			(stroke
				(width 0.1524)
				(type default)
			)
			(layer "F.SilkS")
		)
		(fp_line
			(start 0.9017 1.953768)
			(end 0.9017 0.824484)
			(stroke
				(width 0.1524)
				(type default)
			)
			(layer "F.SilkS")
		)
		(fp_poly
			(pts
				(xy -0.9017 -0.3048) (xy 0.9017 -0.3048) (xy 0.9017 3.0988) (xy -0.9017 3.0988)
			)
			(stroke
				(width 0)
				(type default)
			)
			(fill no)
			(layer "F.CrtYd")
		)
		(fp_line
			(start -0.9017 -0.3048)
			(end -0.9017 3.0988)
			(stroke
				(width 0.1)
				(type default)
			)
			(layer "F.Fab")
		)
		(fp_line
			(start -0.9017 3.0988)
			(end 0.9017 3.0988)
			(stroke
				(width 0.1)
				(type default)
			)
			(layer "F.Fab")
		)
		(fp_line
			(start 0.9017 -0.3048)
			(end -0.9017 -0.3048)
			(stroke
				(width 0.1)
				(type default)
			)
			(layer "F.Fab")
		)
		(fp_line
			(start 0.9017 3.0988)
			(end 0.9017 -0.3048)
			(stroke
				(width 0.1)
				(type default)
			)
			(layer "F.Fab")
		)
		(pad "1" smd rect
			(at 0 0)
			(size 1.524 1.016)
			(layers "F.Cu" "F.Mask" "F.Paste")
			(net "A_HSC_C")
		)
		(pad "2" smd rect
			(at 0 2.794)
			(size 1.524 1.016)
			(layers "F.Cu" "F.Mask" "F.Paste")
			(net "GND")
		)
		(zone
			(layer "F.Cu")
			(hatch none 0.5)
			(connect_pads
				(clearance 0)
			)
			(min_thickness 0.25)
			(keepout
				(tracks allowed)
				(vias not_allowed)
				(pads allowed)
				(copperpour not_allowed)
				(footprints allowed)
			)
			(placement
				(enabled no)
				(sheetname "")
			)
			(fill
				(thermal_gap 0.5)
				(thermal_bridge_width 0.5)
				(island_removal_mode 0)
			)
			(polygon
				(pts
					(xy 27.178 -64.008) (xy 27.178 -62.23) (xy 25.654 -62.23) (xy 25.654 -64.008)
				)
			)
		)
	)
	(footprint ""
		(layer "F.Cu")
		(at 27.423364 -73.744328 90)
		(property "Reference" "RT11"
			(at 1.01473 0.656336 0)
			(unlocked yes)
			(layer "F.SilkS")
			(effects
				(font
					(size 0.4064 0.254)
					(thickness 0.1524)
				)
			)
		)
		(property "Value" ""
			(at 0 0 90)
			(layer "F.Fab")
			(effects
				(font
					(size 1.27 1.27)
				)
			)
		)
		(duplicate_pad_numbers_are_jumpers no)
		(fp_poly
			(pts
				(xy -0.4953 -0.2032) (xy 0.4953 -0.2032) (xy 0.4953 1.6002) (xy -0.4953 1.6002)
			)
			(stroke
				(width 0)
				(type default)
			)
			(fill no)
			(layer "F.CrtYd")
		)
		(fp_line
			(start 0.4953 -0.2032)
			(end 0.4953 1.6002)
			(stroke
				(width 0.1)
				(type default)
			)
			(layer "F.Fab")
		)
		(fp_line
			(start -0.4953 -0.2032)
			(end 0.4953 -0.2032)
			(stroke
				(width 0.1)
				(type default)
			)
			(layer "F.Fab")
		)
		(fp_line
			(start 0.4953 1.6002)
			(end -0.4953 1.6002)
			(stroke
				(width 0.1)
				(type default)
			)
			(layer "F.Fab")
		)
		(fp_line
			(start -0.4953 1.6002)
			(end -0.4953 -0.2032)
			(stroke
				(width 0.1)
				(type default)
			)
			(layer "F.Fab")
		)
		(pad "1" smd rect
			(at 0 0 90)
			(size 0.762 0.889)
			(layers "F.Cu" "F.Mask" "F.Paste")
			(net "VR_PVCCIN_CPU1_PH3_BOOT")
		)
		(pad "2" smd rect
			(at 0 1.397 90)
			(size 0.762 0.889)
			(layers "F.Cu" "F.Mask" "F.Paste")
			(net "VR_PVCCIN_CPU1_PH3_BOOT_R")
		)
		(zone
			(layer "F.Cu")
			(hatch none 0.5)
			(connect_pads
				(clearance 0)
			)
			(min_thickness 0.25)
			(keepout
				(tracks allowed)
				(vias not_allowed)
				(pads allowed)
				(copperpour not_allowed)
				(footprints allowed)
			)
			(placement
				(enabled no)
				(sheetname "")
			)
			(fill
				(thermal_gap 0.5)
				(thermal_bridge_width 0.5)
				(island_removal_mode 0)
			)
			(polygon
				(pts
					(xy 28.375864 -74.125328) (xy 27.867864 -74.125328) (xy 27.867864 -73.363328) (xy 28.375864 -73.363328)
				)
			)
		)
		(zone
			(layer "F.Cu")
			(hatch none 0.5)
			(connect_pads
				(clearance 0)
			)
			(min_thickness 0.25)
			(keepout
				(tracks not_allowed)
				(vias allowed)
				(pads allowed)
				(copperpour not_allowed)
				(footprints allowed)
			)
			(placement
				(enabled no)
				(sheetname "")
			)
			(fill
				(thermal_gap 0.5)
				(thermal_bridge_width 0.5)
				(island_removal_mode 0)
			)
			(polygon
				(pts
					(xy 28.375864 -73.363328) (xy 28.375864 -74.125328) (xy 27.867864 -74.125328) (xy 27.867864 -73.363328)
				)
			)
		)
	)
	(footprint ""
		(layer "F.Cu")
		(at 466.217 -0.2032 90)
		(property "Reference" "C9G22"
			(at 0 0 90)
			(layer "F.SilkS")
			(hide yes)
			(effects
				(font
					(size 1.27 1.27)
				)
			)
		)
		(property "Value" ""
			(at 0 0 90)
			(layer "F.Fab")
			(effects
				(font
					(size 1.27 1.27)
				)
			)
		)
		(duplicate_pad_numbers_are_jumpers no)
		(fp_poly
			(pts
				(xy 0.3048 -0.1016) (xy 0.3048 0.9906) (xy -0.3048 0.9906) (xy -0.3048 -0.1016)
			)
			(stroke
				(width 0)
				(type default)
			)
			(fill no)
			(layer "F.CrtYd")
		)
		(fp_line
			(start 0.3048 -0.1016)
			(end -0.3048 -0.1016)
			(stroke
				(width 0.1)
				(type default)
			)
			(layer "F.Fab")
		)
		(fp_line
			(start -0.3048 -0.1016)
			(end -0.3048 0.9906)
			(stroke
				(width 0.1)
				(type default)
			)
			(layer "F.Fab")
		)
		(fp_line
			(start 0.3048 0.9906)
			(end 0.3048 -0.1016)
			(stroke
				(width 0.1)
				(type default)
			)
			(layer "F.Fab")
		)
		(fp_line
			(start -0.3048 0.9906)
			(end 0.3048 0.9906)
			(stroke
				(width 0.1)
				(type default)
			)
			(layer "F.Fab")
		)
		(pad "1" smd rect
			(at 0 0 90)
			(size 0.508 0.508)
			(layers "F.Cu" "F.Mask" "F.Paste")
			(net "A_P3V_BAT_SCALED")
		)
		(pad "2" smd rect
			(at 0 0.889 90)
			(size 0.508 0.508)
			(layers "F.Cu" "F.Mask" "F.Paste")
			(net "GND")
		)
		(zone
			(layer "F.Cu")
			(hatch none 0.5)
			(connect_pads
				(clearance 0)
			)
			(min_thickness 0.25)
			(keepout
				(tracks allowed)
				(vias not_allowed)
				(pads allowed)
				(copperpour not_allowed)
				(footprints allowed)
			)
			(placement
				(enabled no)
				(sheetname "")
			)
			(fill
				(thermal_gap 0.5)
				(thermal_bridge_width 0.5)
				(island_removal_mode 0)
			)
			(polygon
				(pts
					(xy 466.471 0.0508) (xy 466.471 -0.4572) (xy 466.852 -0.4572) (xy 466.852 0.0508)
				)
			)
		)
		(zone
			(layer "F.Cu")
			(hatch none 0.5)
			(connect_pads
				(clearance 0)
			)
			(min_thickness 0.25)
			(keepout
				(tracks not_allowed)
				(vias allowed)
				(pads allowed)
				(copperpour not_allowed)
				(footprints allowed)
			)
			(placement
				(enabled no)
				(sheetname "")
			)
			(fill
				(thermal_gap 0.5)
				(thermal_bridge_width 0.5)
				(island_removal_mode 0)
			)
			(polygon
				(pts
					(xy 466.852 0.0508) (xy 466.852 -0.4572) (xy 466.471 -0.4572) (xy 466.471 0.0508)
				)
			)
		)
	)
)
